# T6G (Grand Teton) — schematic netlist excerpt (pin names and nets, part order shuffled) for the footprints in the layout excerpt that follows; sources: Cadence DE-HDL packaged netlist, KiCad conversion of 04192023_DAF0TMB3IC0_F0TG_MB_C_brd_V02_OCP.brd

PR599  Q_RES  4.99K 1% EMPTY  pkg 0402LF  page 193 : A = PVDDCR_CPU0_P0_VINSEN ; B = GND
D9  Q_LED  IC  pkg SMLF  page 165 : A = LED_BIOS_DBG_MODE_R ; C = LED_BIOS_DBG_MODE
C864  Q_CAP_DIFFBUS  DIFF BUS_0.22UF 6.3V 20% X6S  pkg C0201  page 64 : \1\ = P5E_CPU0_P2_TX_C_DN<2> ; \2\ = P5E_CPU0_P2_TX_DN<2>

(kicad_pcb
	(version 20260206)
	(generator "pcbnew")
	(generator_version "10.0")
	(general
		(thickness 1.6)
		(legacy_teardrops no)
	)
	(paper "A4")
	(title_block
		(title "04192023_DAF0TMB3IC0_F0TG_MB_C_brd_V02_OCP.brd")
		(comment 1 "Grand Teton / footprints 4593-4595 of 8354")
	)
	(layers
		(0 "F.Cu" signal "TOP")
		(4 "In1.Cu" signal "GND")
		(6 "In2.Cu" signal "IN1")
		(8 "In3.Cu" signal "GND1")
		(10 "In4.Cu" signal "IN2")
		(12 "In5.Cu" signal "GND2")
		(14 "In6.Cu" signal "IN3")
		(16 "In7.Cu" signal "GND3")
		(18 "In8.Cu" signal "VCC")
		(20 "In9.Cu" signal "VCC1")
		(22 "In10.Cu" signal "GND4")
		(24 "In11.Cu" signal "IN4")
		(26 "In12.Cu" signal "GND5")
		(28 "In13.Cu" signal "IN5")
		(30 "In14.Cu" signal "GND6")
		(32 "In15.Cu" signal "IN6")
		(34 "In16.Cu" signal "GND7")
		(2 "B.Cu" signal "BOTTOM")
		(9 "F.Adhes" user "F.Adhesive")
		(11 "B.Adhes" user "B.Adhesive")
		(13 "F.Paste" user "Package Geometry/Pastemask Top")
		(15 "B.Paste" user "Package Geometry/Pastemask Bottom")
		(5 "F.SilkS" user "Ref Des/Silkscreen Top")
		(7 "B.SilkS" user "Ref Des/Silkscreen Bottom")
		(1 "F.Mask" user "Board Geometry/Soldermask Top")
		(3 "B.Mask" user "Board Geometry/Soldermask Bottom")
		(17 "Dwgs.User" user "User.Drawings")
		(19 "Cmts.User" user "User.Comments")
		(21 "Eco1.User" user "User.Eco1")
		(23 "Eco2.User" user "User.Eco2")
		(25 "Edge.Cuts" user "Board Geometry/Outline")
		(27 "Margin" user)
		(31 "F.CrtYd" user "Package Geometry/Place Bound Top")
		(29 "B.CrtYd" user "Package Geometry/Place Bound Bottom")
		(35 "F.Fab" user "Ref Des/Assembly Top")
		(33 "B.Fab" user "Ref Des/Assembly Bottom")
	)
	(footprint ""
		(layer "F.Cu")
		(at 384.113278 -138.170158)
		(property "Reference" "PR599"
			(at 0 0 0)
			(layer "F.SilkS")
			(hide yes)
			(effects
				(font
					(size 1.27 1.27)
				)
			)
		)
		(property "Value" ""
			(at 0 0 0)
			(layer "F.Fab")
			(effects
				(font
					(size 1.27 1.27)
				)
			)
		)
		(duplicate_pad_numbers_are_jumpers no)
		(fp_line
			(start -0.7874 -0.4064)
			(end 0.7874 -0.4064)
			(stroke
				(width 0.1524)
				(type default)
			)
			(layer "F.SilkS")
		)
		(fp_line
			(start -0.7874 0.4064)
			(end -0.7874 -0.4064)
			(stroke
				(width 0.1524)
				(type default)
			)
			(layer "F.SilkS")
		)
		(fp_line
			(start 0.7874 -0.4064)
			(end 0.7874 0.4064)
			(stroke
				(width 0.1524)
				(type default)
			)
			(layer "F.SilkS")
		)
		(fp_line
			(start 0.7874 0.4064)
			(end -0.7874 0.4064)
			(stroke
				(width 0.1524)
				(type default)
			)
			(layer "F.SilkS")
		)
		(fp_line
			(start -0.67945 -0.305054)
			(end -0.12065 -0.305054)
			(stroke
				(width 0.1)
				(type default)
			)
			(layer "F.Fab")
		)
		(fp_line
			(start -0.67945 0.3048)
			(end -0.67945 -0.305054)
			(stroke
				(width 0.1)
				(type default)
			)
			(layer "F.Fab")
		)
		(fp_line
			(start -0.12065 -0.305054)
			(end -0.12065 -0.2794)
			(stroke
				(width 0.1)
				(type default)
			)
			(layer "F.Fab")
		)
		(fp_line
			(start -0.12065 -0.2794)
			(end 0.12065 -0.2794)
			(stroke
				(width 0.1)
				(type default)
			)
			(layer "F.Fab")
		)
		(fp_line
			(start -0.12065 0.2794)
			(end -0.12065 0.3048)
			(stroke
				(width 0.1)
				(type default)
			)
			(layer "F.Fab")
		)
		(fp_line
			(start -0.12065 0.3048)
			(end -0.67945 0.3048)
			(stroke
				(width 0.1)
				(type default)
			)
			(layer "F.Fab")
		)
		(fp_line
			(start 0.120396 0.2794)
			(end -0.12065 0.2794)
			(stroke
				(width 0.1)
				(type default)
			)
			(layer "F.Fab")
		)
		(fp_line
			(start 0.120396 0.3048)
			(end 0.120396 0.2794)
			(stroke
				(width 0.1)
				(type default)
			)
			(layer "F.Fab")
		)
		(fp_line
			(start 0.12065 -0.3048)
			(end 0.67945 -0.3048)
			(stroke
				(width 0.1)
				(type default)
			)
			(layer "F.Fab")
		)
		(fp_line
			(start 0.12065 -0.2794)
			(end 0.12065 -0.3048)
			(stroke
				(width 0.1)
				(type default)
			)
			(layer "F.Fab")
		)
		(fp_line
			(start 0.67945 -0.3048)
			(end 0.67945 0.3048)
			(stroke
				(width 0.1)
				(type default)
			)
			(layer "F.Fab")
		)
		(fp_line
			(start 0.67945 0.3048)
			(end 0.120396 0.3048)
			(stroke
				(width 0.1)
				(type default)
			)
			(layer "F.Fab")
		)
		(pad "1" smd circle
			(at -0.40005 0)
			(size 0 0)
			(layers "F.Cu" "F.Mask" "F.Paste")
			(net "PVDDCR_CPU0_P0_VINSEN")
		)
		(pad "2" smd circle
			(at 0.40005 0)
			(size 0 0)
			(layers "F.Cu" "F.Mask" "F.Paste")
			(net "GND")
		)
	)
	(footprint ""
		(layer "F.Cu")
		(at 399.53184 -381.41783 -90)
		(property "Reference" "C864"
			(at 0 0 270)
			(layer "F.SilkS")
			(hide yes)
			(effects
				(font
					(size 1.27 1.27)
				)
			)
		)
		(property "Value" ""
			(at 0 0 270)
			(layer "F.Fab")
			(effects
				(font
					(size 1.27 1.27)
				)
			)
		)
		(duplicate_pad_numbers_are_jumpers no)
		(fp_line
			(start -0.299974 0.150114)
			(end -0.299974 -0.150114)
			(stroke
				(width 0.1)
				(type default)
			)
			(layer "F.Fab")
		)
		(fp_line
			(start 0.299974 0.150114)
			(end -0.299974 0.150114)
			(stroke
				(width 0.1)
				(type default)
			)
			(layer "F.Fab")
		)
		(fp_line
			(start -0.299974 -0.150114)
			(end 0.299974 -0.150114)
			(stroke
				(width 0.1)
				(type default)
			)
			(layer "F.Fab")
		)
		(fp_line
			(start 0.299974 -0.150114)
			(end 0.299974 0.150114)
			(stroke
				(width 0.1)
				(type default)
			)
			(layer "F.Fab")
		)
		(pad "1" smd rect
			(at -0.2667 0 270)
			(size 0.3048 0.381)
			(layers "F.Cu" "F.Mask" "F.Paste")
			(net "P5E_CPU0_P2_TX_C_DN<2>")
		)
		(pad "2" smd rect
			(at 0.2667 0 270)
			(size 0.3048 0.381)
			(layers "F.Cu" "F.Mask" "F.Paste")
			(net "P5E_CPU0_P2_TX_DN<2>")
		)
	)
	(footprint ""
		(layer "F.Cu")
		(at 336.68462 -15.924276 90)
		(property "Reference" "D9"
			(at -2.94894 0.009652 90)
			(unlocked yes)
			(layer "F.SilkS")
			(effects
				(font
					(size 0.7874 0.5842)
					(thickness 0.1524)
				)
				(justify left)
			)
		)
		(property "Value" ""
			(at 0 0 90)
			(layer "F.Fab")
			(effects
				(font
					(size 1.27 1.27)
				)
			)
		)
		(duplicate_pad_numbers_are_jumpers no)
		(fp_line
			(start 1.16078 -0.4826)
			(end 1.16078 0.4826)
			(stroke
				(width 0.1524)
				(type default)
			)
			(layer "F.SilkS")
		)
		(fp_line
			(start 1.03378 -0.4826)
			(end 1.03378 0.4826)
			(stroke
				(width 0.1524)
				(type default)
			)
			(layer "F.SilkS")
		)
		(fp_line
			(start 0.90678 -0.4826)
			(end 0.90678 0.4826)
			(stroke
				(width 0.1524)
				(type default)
			)
			(layer "F.SilkS")
		)
		(fp_line
			(start -0.64008 -0.4826)
			(end 1.16078 -0.4826)
			(stroke
				(width 0.1524)
				(type default)
			)
			(layer "F.SilkS")
		)
		(fp_line
			(start -0.79248 -0.4826)
			(end 1.03378 -0.4826)
			(stroke
				(width 0.1524)
				(type default)
			)
			(layer "F.SilkS")
		)
		(fp_line
			(start -0.89408 -0.4826)
			(end 0.90678 -0.4826)
			(stroke
				(width 0.1524)
				(type default)
			)
			(layer "F.SilkS")
		)
		(fp_line
			(start 1.16078 0.4826)
			(end -0.64008 0.4826)
			(stroke
				(width 0.1524)
				(type default)
			)
			(layer "F.SilkS")
		)
		(fp_line
			(start 1.03378 0.4826)
			(end -0.79248 0.4826)
			(stroke
				(width 0.1524)
				(type default)
			)
			(layer "F.SilkS")
		)
		(fp_line
			(start 0.90678 0.4826)
			(end -0.90678 0.4826)
			(stroke
				(width 0.1524)
				(type default)
			)
			(layer "F.SilkS")
		)
		(fp_line
			(start -0.90678 0.4826)
			(end -0.90678 -0.4699)
			(stroke
				(width 0.1524)
				(type default)
			)
			(layer "F.SilkS")
		)
		(fp_line
			(start 0.499872 -0.249936)
			(end 0.499872 0.249936)
			(stroke
				(width 0.1)
				(type default)
			)
			(layer "F.Fab")
		)
		(fp_line
			(start -0.499872 -0.249936)
			(end 0.499872 -0.249936)
			(stroke
				(width 0.1)
				(type default)
			)
			(layer "F.Fab")
		)
		(fp_line
			(start 0.499872 0.249936)
			(end -0.499872 0.249936)
			(stroke
				(width 0.1)
				(type default)
			)
			(layer "F.Fab")
		)
		(fp_line
			(start -0.499872 0.249936)
			(end -0.499872 -0.249936)
			(stroke
				(width 0.1)
				(type default)
			)
			(layer "F.Fab")
		)
		(pad "A" smd rect
			(at -0.47498 0 90)
			(size 0.6096 0.7112)
			(layers "F.Cu" "F.Mask" "F.Paste")
			(net "LED_BIOS_DBG_MODE_R")
		)
		(pad "C" smd rect
			(at 0.47498 0 90)
			(size 0.6096 0.7112)
			(layers "F.Cu" "F.Mask" "F.Paste")
			(net "LED_BIOS_DBG_MODE")
		)
	)
)
